(kicad_pcb
	(version 20241229)
	(generator "pcbnew")
	(generator_version "9.0")
	(general
		(thickness 1.711)
		(legacy_teardrops no)
	)
	(paper "A4")
	(title_block
		(title "Antmicro Baseboard for Jetson AGX Thor")
		(date "2026-02-18")
		(rev "1.1.0")
		(company "Antmicro Ltd")
		(comment 1 "www.antmicro.com")
		(comment 9 "footprints 150-153 of 1170")
	)
	(layers
		(0 "F.Cu" signal)
		(4 "In1.Cu" signal)
		(6 "In2.Cu" signal)
		(8 "In3.Cu" signal)
		(10 "In4.Cu" jumper)
		(12 "In5.Cu" signal)
		(14 "In6.Cu" signal)
		(16 "In7.Cu" signal)
		(18 "In8.Cu" signal)
		(2 "B.Cu" signal)
		(9 "F.Adhes" user "F.Adhesive")
		(11 "B.Adhes" user "B.Adhesive")
		(13 "F.Paste" user)
		(15 "B.Paste" user)
		(5 "F.SilkS" user "F.Silkscreen")
		(7 "B.SilkS" user "B.Silkscreen")
		(1 "F.Mask" user)
		(3 "B.Mask" user)
		(17 "Dwgs.User" user "User.Drawings")
		(19 "Cmts.User" user "User.Comments")
		(21 "Eco1.User" user "User.Eco1")
		(23 "Eco2.User" user "User.Eco2")
		(25 "Edge.Cuts" user)
		(27 "Margin" user)
		(31 "F.CrtYd" user "F.Courtyard")
		(29 "B.CrtYd" user "B.Courtyard")
		(35 "F.Fab" user)
		(33 "B.Fab" user)
	)
	(footprint "antmicro-footprints:USON-10_2.5x1mm_P0.5mm"
		(layer "F.Cu")
		(at 220.853 125.425 180)
		(descr "USON-10 2.5x1mm_ Pitch 0.5mm")
		(tags "USON-10 2.5x1mm Pitch 0.5mm")
		(property "Reference" "U17"
			(at -1.137 -2.405 90)
			(layer "F.SilkS")
			(effects
				(font
					(size 0.7 0.7)
					(thickness 0.15)
				)
				(justify right top)
			)
		)
		(property "Value" "TPD4E05U06QDQARQ1"
			(at 0.018 2.499 0)
			(layer "F.Fab")
			(effects
				(font
					(size 0.7 0.7)
					(thickness 0.15)
				)
				(justify right top)
			)
		)
		(property "Datasheet" "https://www.ti.com/lit/ds/symlink/tpd4e05u06-q1.pdf?HQS=dis-mous-null-mousermode-dsf-pf-null-wwe&ts=1663591265741&ref_url=https%253A%252F%252Fwww.mouser.com%252F"
			(at 0 0 0)
			(layer "F.Fab")
			(hide yes)
			(effects
				(font
					(size 1.27 1.27)
					(thickness 0.15)
				)
			)
		)
		(property "Description" "TVS diode array, 12 kV, USON-10, 5.5 V, 0.5 pF"
			(at 0 0 0)
			(layer "F.Fab")
			(hide yes)
			(effects
				(font
					(size 1.27 1.27)
					(thickness 0.15)
				)
			)
		)
		(property "Manufacturer" "Texas Instruments"
			(at 0 0 180)
			(unlocked yes)
			(layer "F.Fab")
			(hide yes)
			(effects
				(font
					(size 1 1)
					(thickness 0.15)
				)
			)
		)
		(property "MPN" "TPD4E05U06QDQARQ1"
			(at 0 0 180)
			(unlocked yes)
			(layer "F.Fab")
			(hide yes)
			(effects
				(font
					(size 1 1)
					(thickness 0.15)
				)
			)
		)
		(property "Author" "Antmicro"
			(at 0 0 180)
			(unlocked yes)
			(layer "F.Fab")
			(hide yes)
			(effects
				(font
					(size 1 1)
					(thickness 0.15)
				)
			)
		)
		(property "License" "Apache-2.0"
			(at 0 0 180)
			(unlocked yes)
			(layer "F.Fab")
			(hide yes)
			(effects
				(font
					(size 1 1)
					(thickness 0.15)
				)
			)
		)
		(sheetname "/USB Hub/")
		(sheetfile "usb_hub.kicad_sch")
		(attr smd)
		(fp_line
			(start 0.498 1.398)
			(end -0.5 1.398)
			(stroke
				(width 0.15)
				(type solid)
			)
			(layer "F.SilkS")
		)
		(fp_line
			(start 0.498 -1.401)
			(end -0.5 -1.401)
			(stroke
				(width 0.15)
				(type solid)
			)
			(layer "F.SilkS")
		)
		(fp_circle
			(center -0.68 -1.27)
			(end -0.63 -1.27)
			(stroke
				(width 0.15)
				(type solid)
			)
			(fill yes)
			(layer "F.SilkS")
		)
		(fp_rect
			(start -0.8 -1.5)
			(end 0.8 1.499)
			(stroke
				(width 0.05)
				(type solid)
			)
			(fill no)
			(layer "F.CrtYd")
		)
		(fp_line
			(start 0.498 -1.25)
			(end 0.498 1.249)
			(stroke
				(width 0.15)
				(type solid)
			)
			(layer "F.Fab")
		)
		(fp_line
			(start 0.498 -1.25)
			(end -0.25 -1.25)
			(stroke
				(width 0.15)
				(type solid)
			)
			(layer "F.Fab")
		)
		(fp_line
			(start -0.25 -1.25)
			(end -0.5 -1)
			(stroke
				(width 0.15)
				(type solid)
			)
			(layer "F.Fab")
		)
		(fp_line
			(start -0.5 1.249)
			(end 0.498 1.249)
			(stroke
				(width 0.15)
				(type solid)
			)
			(layer "F.Fab")
		)
		(fp_line
			(start -0.5 -1)
			(end -0.5 1.249)
			(stroke
				(width 0.15)
				(type solid)
			)
			(layer "F.Fab")
		)
		(fp_text user "Author: Antmicro"
			(at -0.802 5.7 0)
			(layer "F.Fab")
			(effects
				(font
					(size 0.7 0.7)
					(thickness 0.15)
				)
				(justify right top)
			)
		)
		(fp_text user "License: Apache-2.0"
			(at -0.802 6.9 0)
			(layer "F.Fab")
			(effects
				(font
					(size 0.7 0.7)
					(thickness 0.15)
				)
				(justify right top)
			)
		)
		(fp_text user "${REFERENCE}"
			(at -0.802 4.498 0)
			(layer "F.Fab")
			(effects
				(font
					(size 0.7 0.7)
					(thickness 0.15)
				)
				(justify right top)
			)
		)
		(pad "1" smd roundrect
			(at -0.387 -1 90)
			(size 0.25 0.55)
			(layers "F.Cu" "F.Mask" "F.Paste")
			(roundrect_rratio 0.25)
			(net 80 "/USB Hub/USBC4_CONN_TX2_P")
			(pintype "passive")
		)
		(pad "2" smd roundrect
			(at -0.387 -0.5 90)
			(size 0.25 0.55)
			(layers "F.Cu" "F.Mask" "F.Paste")
			(roundrect_rratio 0.25)
			(net 110 "/USB Hub/USBC4_CONN_TX2_N")
			(pintype "passive")
		)
		(pad "3" smd roundrect
			(at -0.387 0 90)
			(size 0.4 0.55)
			(layers "F.Cu" "F.Mask" "F.Paste")
			(roundrect_rratio 0.25)
			(net 1 "GND")
			(pintype "power_in")
		)
		(pad "4" smd roundrect
			(at -0.387 0.498 90)
			(size 0.25 0.55)
			(layers "F.Cu" "F.Mask" "F.Paste")
			(roundrect_rratio 0.25)
			(net 498 "/USB Hub/USBC4_RX_{2}+")
			(pintype "passive")
		)
		(pad "5" smd roundrect
			(at -0.387 0.998 90)
			(size 0.25 0.55)
			(layers "F.Cu" "F.Mask" "F.Paste")
			(roundrect_rratio 0.25)
			(net 500 "/USB Hub/USBC4_RX_{2}-")
			(pintype "passive")
		)
		(pad "6" smd roundrect
			(at 0.385 0.998 90)
			(size 0.25 0.55)
			(layers "F.Cu" "F.Mask" "F.Paste")
			(roundrect_rratio 0.25)
			(net 500 "/USB Hub/USBC4_RX_{2}-")
			(pintype "passive")
		)
		(pad "7" smd roundrect
			(at 0.385 0.498 90)
			(size 0.25 0.55)
			(layers "F.Cu" "F.Mask" "F.Paste")
			(roundrect_rratio 0.25)
			(net 498 "/USB Hub/USBC4_RX_{2}+")
			(pintype "passive")
		)
		(pad "8" smd roundrect
			(at 0.385 0 90)
			(size 0.4 0.55)
			(layers "F.Cu" "F.Mask" "F.Paste")
			(roundrect_rratio 0.25)
			(net 1 "GND")
			(pintype "passive")
		)
		(pad "9" smd roundrect
			(at 0.385 -0.5 90)
			(size 0.25 0.55)
			(layers "F.Cu" "F.Mask" "F.Paste")
			(roundrect_rratio 0.25)
			(net 110 "/USB Hub/USBC4_CONN_TX2_N")
			(pintype "passive")
		)
		(pad "10" smd roundrect
			(at 0.385 -1 90)
			(size 0.25 0.55)
			(layers "F.Cu" "F.Mask" "F.Paste")
			(roundrect_rratio 0.25)
			(net 80 "/USB Hub/USBC4_CONN_TX2_P")
			(pintype "passive")
		)
	)
	(footprint "antmicro-footprints:C_0402_1005Metric"
		(layer "F.Cu")
		(at 204.75 89.970856 180)
		(descr "Capacitor SMD 0402")
		(tags "capacitor SMD 0402")
		(property "Reference" "C318"
			(at 5.25 -0.429144 180)
			(layer "F.SilkS")
			(effects
				(font
					(size 0.7 0.7)
					(thickness 0.15)
				)
				(justify left bottom)
			)
		)
		(property "Value" "C_100n_0402"
			(at -1.022927 2.155213 180)
			(layer "F.Fab")
			(effects
				(font
					(size 0.7 0.7)
					(thickness 0.15)
				)
				(justify left bottom)
			)
		)
		(property "Datasheet" "https://www.murata.com/products/productdetail?partno=GRM155R61H104KE14%23"
			(at 0 0 180)
			(layer "F.Fab")
			(hide yes)
			(effects
				(font
					(size 1.27 1.27)
					(thickness 0.15)
				)
			)
		)
		(property "Description" "SMD Multilayer Ceramic Capacitor, 0.1 µF, 50 V, 0402 [1005 Metric], ± 10%, X5R, GRM Series"
			(at 0 0 180)
			(layer "F.Fab")
			(hide yes)
			(effects
				(font
					(size 1.27 1.27)
					(thickness 0.15)
				)
			)
		)
		(property "Manufacturer" "Murata"
			(at 0 0 180)
			(unlocked yes)
			(layer "F.Fab")
			(hide yes)
			(effects
				(font
					(size 1 1)
					(thickness 0.15)
				)
			)
		)
		(property "MPN" "GRM155R61H104KE14D"
			(at 0 0 180)
			(unlocked yes)
			(layer "F.Fab")
			(hide yes)
			(effects
				(font
					(size 1 1)
					(thickness 0.15)
				)
			)
		)
		(property "Val" "100n"
			(at 0 0 180)
			(unlocked yes)
			(layer "F.Fab")
			(hide yes)
			(effects
				(font
					(size 1 1)
					(thickness 0.15)
				)
			)
		)
		(property "License" "Apache-2.0"
			(at 0 0 180)
			(unlocked yes)
			(layer "F.Fab")
			(hide yes)
			(effects
				(font
					(size 1 1)
					(thickness 0.15)
				)
			)
		)
		(property "Author" "Antmicro"
			(at 0 0 180)
			(unlocked yes)
			(layer "F.Fab")
			(hide yes)
			(effects
				(font
					(size 1 1)
					(thickness 0.15)
				)
			)
		)
		(property "Voltage" "50V"
			(at 0 0 180)
			(unlocked yes)
			(layer "F.Fab")
			(hide yes)
			(effects
				(font
					(size 1 1)
					(thickness 0.15)
				)
			)
		)
		(property "Dielectric" "X5R"
			(at 0 0 180)
			(unlocked yes)
			(layer "F.Fab")
			(hide yes)
			(effects
				(font
					(size 1 1)
					(thickness 0.15)
				)
			)
		)
		(sheetname "/SoM_IO2/")
		(sheetfile "som_io2.kicad_sch")
		(attr smd)
		(fp_rect
			(start -0.925 -0.47)
			(end 0.925 0.47)
			(stroke
				(width 0.05)
				(type default)
			)
			(fill no)
			(layer "F.CrtYd")
		)
		(fp_line
			(start 0.504 0.248)
			(end -0.494 0.248)
			(stroke
				(width 0.15)
				(type solid)
			)
			(layer "F.Fab")
		)
		(fp_line
			(start 0.504 -0.25)
			(end 0.504 0.248)
			(stroke
				(width 0.15)
				(type solid)
			)
			(layer "F.Fab")
		)
		(fp_line
			(start -0.494 0.248)
			(end -0.494 -0.25)
			(stroke
				(width 0.15)
				(type solid)
			)
			(layer "F.Fab")
		)
		(fp_line
			(start -0.494 -0.25)
			(end 0.504 -0.25)
			(stroke
				(width 0.15)
				(type solid)
			)
			(layer "F.Fab")
		)
		(fp_text user "Author: Antmicro"
			(at -0.939 3.399 180)
			(layer "F.Fab")
			(effects
				(font
					(size 0.7 0.7)
					(thickness 0.15)
				)
				(justify left bottom)
			)
		)
		(fp_text user "License: Apache-2.0"
			(at -0.939 5.799 180)
			(layer "F.Fab")
			(effects
				(font
					(size 0.7 0.7)
					(thickness 0.15)
				)
				(justify left bottom)
			)
		)
		(fp_text user "${REFERENCE}"
			(at -0.939 4.599 180)
			(layer "F.Fab")
			(effects
				(font
					(size 0.7 0.7)
					(thickness 0.15)
				)
				(justify left bottom)
			)
		)
		(pad "1" smd roundrect
			(at -0.48 0 180)
			(size 0.59 0.64)
			(layers "F.Cu" "F.Mask" "F.Paste")
			(roundrect_rratio 0.25)
			(net 786 "/SoM_IO2/DP0.TX2+")
			(pintype "passive")
		)
		(pad "2" smd roundrect
			(at 0.48 0 180)
			(size 0.59 0.64)
			(layers "F.Cu" "F.Mask" "F.Paste")
			(roundrect_rratio 0.25)
			(net 615 "/SoM_IO2/DP0.TX2_C+")
			(pintype "passive")
		)
	)
	(footprint "antmicro-footprints:C_0402_1005Metric"
		(layer "F.Cu")
		(at 82.1 75.8 -90)
		(descr "Capacitor SMD 0402")
		(tags "capacitor SMD 0402")
		(property "Reference" "C343"
			(at 0.9 0.4 90)
			(layer "F.SilkS")
			(effects
				(font
					(size 0.7 0.7)
					(thickness 0.15)
				)
				(justify right top)
			)
		)
		(property "Value" "C_100n_0402"
			(at -1.022927 2.155213 90)
			(layer "F.Fab")
			(effects
				(font
					(size 0.7 0.7)
					(thickness 0.15)
				)
				(justify right top)
			)
		)
		(property "Datasheet" "https://www.murata.com/products/productdetail?partno=GRM155R61H104KE14%23"
			(at 0 0 90)
			(layer "F.Fab")
			(hide yes)
			(effects
				(font
					(size 1.27 1.27)
					(thickness 0.15)
				)
			)
		)
		(property "Description" "SMD Multilayer Ceramic Capacitor, 0.1 µF, 50 V, 0402 [1005 Metric], ± 10%, X5R, GRM Series"
			(at 0 0 90)
			(layer "F.Fab")
			(hide yes)
			(effects
				(font
					(size 1.27 1.27)
					(thickness 0.15)
				)
			)
		)
		(property "Manufacturer" "Murata"
			(at 0 0 270)
			(unlocked yes)
			(layer "F.Fab")
			(hide yes)
			(effects
				(font
					(size 1 1)
					(thickness 0.15)
				)
			)
		)
		(property "MPN" "GRM155R61H104KE14D"
			(at 0 0 270)
			(unlocked yes)
			(layer "F.Fab")
			(hide yes)
			(effects
				(font
					(size 1 1)
					(thickness 0.15)
				)
			)
		)
		(property "Val" "100n"
			(at 0 0 270)
			(unlocked yes)
			(layer "F.Fab")
			(hide yes)
			(effects
				(font
					(size 1 1)
					(thickness 0.15)
				)
			)
		)
		(property "License" "Apache-2.0"
			(at 0 0 270)
			(unlocked yes)
			(layer "F.Fab")
			(hide yes)
			(effects
				(font
					(size 1 1)
					(thickness 0.15)
				)
			)
		)
		(property "Author" "Antmicro"
			(at 0 0 270)
			(unlocked yes)
			(layer "F.Fab")
			(hide yes)
			(effects
				(font
					(size 1 1)
					(thickness 0.15)
				)
			)
		)
		(property "Voltage" "50V"
			(at 0 0 270)
			(unlocked yes)
			(layer "F.Fab")
			(hide yes)
			(effects
				(font
					(size 1 1)
					(thickness 0.15)
				)
			)
		)
		(property "Dielectric" "X5R"
			(at 0 0 270)
			(unlocked yes)
			(layer "F.Fab")
			(hide yes)
			(effects
				(font
					(size 1 1)
					(thickness 0.15)
				)
			)
		)
		(sheetname "/SoM_IO2/")
		(sheetfile "som_io2.kicad_sch")
		(attr smd)
		(fp_poly
			(pts
				(xy -0.925 -0.47) (xy 0.925 -0.47) (xy 0.925 0.47) (xy -0.925 0.47)
			)
			(stroke
				(width 0.05)
				(type default)
			)
			(fill no)
			(layer "F.CrtYd")
		)
		(fp_line
			(start -0.494 0.248)
			(end -0.494 -0.25)
			(stroke
				(width 0.15)
				(type solid)
			)
			(layer "F.Fab")
		)
		(fp_line
			(start 0.504 0.248)
			(end -0.494 0.248)
			(stroke
				(width 0.15)
				(type solid)
			)
			(layer "F.Fab")
		)
		(fp_line
			(start -0.494 -0.25)
			(end 0.504 -0.25)
			(stroke
				(width 0.15)
				(type solid)
			)
			(layer "F.Fab")
		)
		(fp_line
			(start 0.504 -0.25)
			(end 0.504 0.248)
			(stroke
				(width 0.15)
				(type solid)
			)
			(layer "F.Fab")
		)
		(fp_text user "Author: Antmicro"
			(at -0.939 3.399 90)
			(layer "F.Fab")
			(effects
				(font
					(size 0.7 0.7)
					(thickness 0.15)
				)
				(justify right top)
			)
		)
		(fp_text user "${REFERENCE}"
			(at -0.939 4.599 90)
			(layer "F.Fab")
			(effects
				(font
					(size 0.7 0.7)
					(thickness 0.15)
				)
				(justify right top)
			)
		)
		(fp_text user "License: Apache-2.0"
			(at -0.939 5.799 90)
			(layer "F.Fab")
			(effects
				(font
					(size 0.7 0.7)
					(thickness 0.15)
				)
				(justify right top)
			)
		)
		(pad "1" smd roundrect
			(at -0.48 0 270)
			(size 0.59 0.64)
			(layers "F.Cu" "F.Mask" "F.Paste")
			(roundrect_rratio 0.25)
			(net 1263 "/SoM_IO2/DP2.AUX_C-")
			(pintype "passive")
		)
		(pad "2" smd roundrect
			(at 0.48 0 270)
			(size 0.59 0.64)
			(layers "F.Cu" "F.Mask" "F.Paste")
			(roundrect_rratio 0.25)
			(net 656 "/Expansion connector/DP2.AUX-")
			(pintype "passive")
		)
	)
	(footprint "antmicro-footprints:C_0603_1608Metric_EIA"
		(layer "F.Cu")
		(at 193.9 122.7)
		(descr "Capacitor SMD 0603, IPC-7351 Density Level A")
		(tags "Capacitor 0603")
		(property "Reference" "C311"
			(at -0.5 -0.65 0)
			(layer "F.SilkS")
			(effects
				(font
					(size 0.7 0.7)
					(thickness 0.15)
				)
				(justify left bottom)
			)
		)
		(property "Value" "C_22u_16V_0603"
			(at -1.42757 1.770288 0)
			(layer "F.Fab")
			(effects
				(font
					(size 0.7 0.7)
					(thickness 0.15)
				)
				(justify left bottom)
			)
		)
		(property "Datasheet" "https://product.samsungsem.com/mlcc/CL10A226MO7JZN.do"
			(at 0 0 0)
			(layer "F.Fab")
			(hide yes)
			(effects
				(font
					(size 1.27 1.27)
					(thickness 0.15)
				)
			)
		)
		(property "Description" "SMD Multilayer Ceramic Capacitor"
			(at 0 0 0)
			(layer "F.Fab")
			(hide yes)
			(effects
				(font
					(size 1.27 1.27)
					(thickness 0.15)
				)
			)
		)
		(property "Manufacturer" "Samsung Electro-Mechanics"
			(at 0 0 0)
			(unlocked yes)
			(layer "F.Fab")
			(hide yes)
			(effects
				(font
					(size 1 1)
					(thickness 0.15)
				)
			)
		)
		(property "MPN" "CL10A226MO7JZNC"
			(at 0 0 0)
			(unlocked yes)
			(layer "F.Fab")
			(hide yes)
			(effects
				(font
					(size 1 1)
					(thickness 0.15)
				)
			)
		)
		(property "Val" "22u"
			(at 0 0 0)
			(unlocked yes)
			(layer "F.Fab")
			(hide yes)
			(effects
				(font
					(size 1 1)
					(thickness 0.15)
				)
			)
		)
		(property "License" "Apache-2.0"
			(at 0 0 0)
			(unlocked yes)
			(layer "F.Fab")
			(hide yes)
			(effects
				(font
					(size 1 1)
					(thickness 0.15)
				)
			)
		)
		(property "Author" "Antmicro"
			(at 0 0 0)
			(unlocked yes)
			(layer "F.Fab")
			(hide yes)
			(effects
				(font
					(size 1 1)
					(thickness 0.15)
				)
			)
		)
		(property "Voltage" "16V"
			(at 0 0 0)
			(unlocked yes)
			(layer "F.Fab")
			(hide yes)
			(effects
				(font
					(size 1 1)
					(thickness 0.15)
				)
			)
		)
		(property "Dielectric" ""
			(at 0 0 0)
			(unlocked yes)
			(layer "F.Fab")
			(hide yes)
			(effects
				(font
					(size 1 1)
					(thickness 0.15)
				)
			)
		)
		(sheetname "/USB Hub/")
		(sheetfile "usb_hub.kicad_sch")
		(attr smd)
		(fp_line
			(start -0.15 -0.55)
			(end 0.15 -0.55)
			(stroke
				(width 0.15)
				(type solid)
			)
			(layer "F.SilkS")
		)
		(fp_line
			(start -0.15 0.55)
			(end 0.15 0.55)
			(stroke
				(width 0.15)
				(type solid)
			)
			(layer "F.SilkS")
		)
		(fp_rect
			(start -1.25 -0.65)
			(end 1.25 0.65)
			(stroke
				(width 0.05)
				(type solid)
			)
			(fill no)
			(layer "F.CrtYd")
		)
		(fp_rect
			(start -0.8 -0.45)
			(end 0.8 0.45)
			(stroke
				(width 0.15)
				(type solid)
			)
			(fill no)
			(layer "F.Fab")
		)
		(fp_text user "License: Apache-2.0"
			(at -1.682 5.895 0)
			(layer "F.Fab")
			(effects
				(font
					(size 0.7 0.7)
					(thickness 0.15)
				)
				(justify left bottom)
			)
		)
		(fp_text user "Author: Antmicro"
			(at -1.682 4.894 0)
			(layer "F.Fab")
			(effects
				(font
					(size 0.7 0.7)
					(thickness 0.15)
				)
				(justify left bottom)
			)
		)
		(fp_text user "${REFERENCE}"
			(at -1.682 3.895 0)
			(layer "F.Fab")
			(effects
				(font
					(size 0.7 0.7)
					(thickness 0.15)
				)
				(justify left bottom)
			)
		)
		(pad "1" smd roundrect
			(at -0.7 0)
			(size 0.8 1.1)
			(layers "F.Cu" "F.Mask" "F.Paste")
			(roundrect_rratio 0.2)
			(net 1 "GND")
			(pintype "passive")
		)
		(pad "2" smd roundrect
			(at 0.7 0)
			(size 0.8 1.1)
			(layers "F.Cu" "F.Mask" "F.Paste")
			(roundrect_rratio 0.2)
			(net 282 "+1V15")
			(pintype "passive")
		)
	)
)
